(kicad_pcb
	(version 20260206)
	(generator "pcbnew")
	(generator_version "10.0")
	(general
		(thickness 1.6)
		(legacy_teardrops no)
	)
	(paper "A4")
	(title_block
		(title "03242023_DA0F0TMBIJ0_F0T_Motherboard_J_brd_V01_OCP.brd")
		(comment 1 "Grand Teton / footprints 2201-2206 of 6105")
	)
	(layers
		(0 "F.Cu" signal "TOP")
		(4 "In1.Cu" signal "GND")
		(6 "In2.Cu" signal "IN1")
		(8 "In3.Cu" signal "GND1")
		(10 "In4.Cu" signal "IN2")
		(12 "In5.Cu" signal "GND2")
		(14 "In6.Cu" signal "IN3")
		(16 "In7.Cu" signal "GND3")
		(18 "In8.Cu" signal "VCC")
		(20 "In9.Cu" signal "VCC1")
		(22 "In10.Cu" signal "GND4")
		(24 "In11.Cu" signal "IN4")
		(26 "In12.Cu" signal "GND5")
		(28 "In13.Cu" signal "IN5")
		(30 "In14.Cu" signal "GND6")
		(32 "In15.Cu" signal "IN6")
		(34 "In16.Cu" signal "GND7")
		(2 "B.Cu" signal "BOTTOM")
		(9 "F.Adhes" user "F.Adhesive")
		(11 "B.Adhes" user "B.Adhesive")
		(13 "F.Paste" user "Package Geometry/Pastemask Top")
		(15 "B.Paste" user "Package Geometry/Pastemask Bottom")
		(5 "F.SilkS" user "Ref Des/Silkscreen Top")
		(7 "B.SilkS" user "Ref Des/Silkscreen Bottom")
		(1 "F.Mask" user "Board Geometry/Soldermask Top")
		(3 "B.Mask" user "Board Geometry/Soldermask Bottom")
		(17 "Dwgs.User" user "User.Drawings")
		(19 "Cmts.User" user "User.Comments")
		(21 "Eco1.User" user "User.Eco1")
		(23 "Eco2.User" user "User.Eco2")
		(25 "Edge.Cuts" user "Board Geometry/Outline")
		(27 "Margin" user)
		(31 "F.CrtYd" user "Package Geometry/Place Bound Top")
		(29 "B.CrtYd" user "Package Geometry/Place Bound Bottom")
		(35 "F.Fab" user "Ref Des/Assembly Top")
		(33 "B.Fab" user "Ref Des/Assembly Bottom")
	)
	(footprint ""
		(layer "F.Cu")
		(at 374.336056 -352.812858)
		(property "Reference" "PC1247"
			(at 0 0 0)
			(layer "F.SilkS")
			(hide yes)
			(effects
				(font
					(size 1.27 1.27)
				)
			)
		)
		(property "Value" ""
			(at 0 0 0)
			(layer "F.Fab")
			(effects
				(font
					(size 1.27 1.27)
				)
			)
		)
		(duplicate_pad_numbers_are_jumpers no)
		(fp_line
			(start -1.524 -0.762)
			(end 1.524 -0.762)
			(stroke
				(width 0.1524)
				(type default)
			)
			(layer "F.SilkS")
		)
		(fp_line
			(start -1.524 0.762)
			(end -1.524 -0.762)
			(stroke
				(width 0.1524)
				(type default)
			)
			(layer "F.SilkS")
		)
		(fp_line
			(start 1.524 -0.762)
			(end 1.524 0.762)
			(stroke
				(width 0.1524)
				(type default)
			)
			(layer "F.SilkS")
		)
		(fp_line
			(start 1.524 0.762)
			(end -1.524 0.762)
			(stroke
				(width 0.1524)
				(type default)
			)
			(layer "F.SilkS")
		)
		(fp_line
			(start -1.1049 -0.724916)
			(end -1.1049 0.724916)
			(stroke
				(width 0.1)
				(type default)
			)
			(layer "F.Fab")
		)
		(fp_line
			(start -1.1049 0.724916)
			(end 1.1049 0.724916)
			(stroke
				(width 0.1)
				(type default)
			)
			(layer "F.Fab")
		)
		(fp_line
			(start 1.1049 -0.724916)
			(end -1.1049 -0.724916)
			(stroke
				(width 0.1)
				(type default)
			)
			(layer "F.Fab")
		)
		(fp_line
			(start 1.1049 0.724916)
			(end 1.1049 -0.724916)
			(stroke
				(width 0.1)
				(type default)
			)
			(layer "F.Fab")
		)
		(pad "1" smd rect
			(at -0.889 0 180)
			(size 1.016 1.27)
			(layers "F.Cu" "F.Mask" "F.Paste")
			(net "SW_P12V_PVCCIN_CPU0_FLT")
		)
		(pad "2" smd rect
			(at 0.889 0 180)
			(size 1.016 1.27)
			(layers "F.Cu" "F.Mask" "F.Paste")
			(net "GND")
		)
	)
	(footprint ""
		(layer "F.Cu")
		(at 354.93071 -338.180172 -90)
		(property "Reference" "PC300"
			(at 0 0 270)
			(layer "F.SilkS")
			(hide yes)
			(effects
				(font
					(size 1.27 1.27)
				)
			)
		)
		(property "Value" ""
			(at 0 0 270)
			(layer "F.Fab")
			(effects
				(font
					(size 1.27 1.27)
				)
			)
		)
		(duplicate_pad_numbers_are_jumpers no)
		(fp_line
			(start -0.7874 0.4064)
			(end -0.7874 -0.4064)
			(stroke
				(width 0.1524)
				(type default)
			)
			(layer "F.SilkS")
		)
		(fp_line
			(start 0.7874 0.4064)
			(end -0.7874 0.4064)
			(stroke
				(width 0.1524)
				(type default)
			)
			(layer "F.SilkS")
		)
		(fp_line
			(start -0.7874 -0.4064)
			(end 0.7874 -0.4064)
			(stroke
				(width 0.1524)
				(type default)
			)
			(layer "F.SilkS")
		)
		(fp_line
			(start 0.7874 -0.4064)
			(end 0.7874 0.4064)
			(stroke
				(width 0.1524)
				(type default)
			)
			(layer "F.SilkS")
		)
		(fp_line
			(start -0.67945 0.3048)
			(end -0.67945 -0.305054)
			(stroke
				(width 0.1)
				(type default)
			)
			(layer "F.Fab")
		)
		(fp_line
			(start -0.12065 0.3048)
			(end -0.67945 0.3048)
			(stroke
				(width 0.1)
				(type default)
			)
			(layer "F.Fab")
		)
		(fp_line
			(start 0.120396 0.3048)
			(end 0.120396 0.2794)
			(stroke
				(width 0.1)
				(type default)
			)
			(layer "F.Fab")
		)
		(fp_line
			(start 0.67945 0.3048)
			(end 0.120396 0.3048)
			(stroke
				(width 0.1)
				(type default)
			)
			(layer "F.Fab")
		)
		(fp_line
			(start -0.12065 0.2794)
			(end -0.12065 0.3048)
			(stroke
				(width 0.1)
				(type default)
			)
			(layer "F.Fab")
		)
		(fp_line
			(start 0.120396 0.2794)
			(end -0.12065 0.2794)
			(stroke
				(width 0.1)
				(type default)
			)
			(layer "F.Fab")
		)
		(fp_line
			(start -0.12065 -0.2794)
			(end 0.12065 -0.2794)
			(stroke
				(width 0.1)
				(type default)
			)
			(layer "F.Fab")
		)
		(fp_line
			(start 0.12065 -0.2794)
			(end 0.12065 -0.3048)
			(stroke
				(width 0.1)
				(type default)
			)
			(layer "F.Fab")
		)
		(fp_line
			(start 0.12065 -0.3048)
			(end 0.67945 -0.3048)
			(stroke
				(width 0.1)
				(type default)
			)
			(layer "F.Fab")
		)
		(fp_line
			(start 0.67945 -0.3048)
			(end 0.67945 0.3048)
			(stroke
				(width 0.1)
				(type default)
			)
			(layer "F.Fab")
		)
		(fp_line
			(start -0.67945 -0.305054)
			(end -0.12065 -0.305054)
			(stroke
				(width 0.1)
				(type default)
			)
			(layer "F.Fab")
		)
		(fp_line
			(start -0.12065 -0.305054)
			(end -0.12065 -0.2794)
			(stroke
				(width 0.1)
				(type default)
			)
			(layer "F.Fab")
		)
		(pad "1" smd circle
			(at -0.40005 0 270)
			(size 0 0)
			(layers "F.Cu" "F.Mask" "F.Paste")
			(net "SW_PVCCIN_CPU0_BOOT2_R")
		)
		(pad "2" smd circle
			(at 0.40005 0 270)
			(size 0 0)
			(layers "F.Cu" "F.Mask" "F.Paste")
			(net "SW_PVCCIN_CPU0_BOOTR2")
		)
	)
	(footprint ""
		(layer "F.Cu")
		(at 29.13888 -427.192948 -90)
		(property "Reference" "C1957"
			(at 0 0 270)
			(layer "F.SilkS")
			(hide yes)
			(effects
				(font
					(size 1.27 1.27)
				)
			)
		)
		(property "Value" ""
			(at 0 0 270)
			(layer "F.Fab")
			(effects
				(font
					(size 1.27 1.27)
				)
			)
		)
		(duplicate_pad_numbers_are_jumpers no)
		(fp_line
			(start -0.7874 0.4064)
			(end -0.7874 -0.4064)
			(stroke
				(width 0.1524)
				(type default)
			)
			(layer "F.SilkS")
		)
		(fp_line
			(start 0.7874 0.4064)
			(end -0.7874 0.4064)
			(stroke
				(width 0.1524)
				(type default)
			)
			(layer "F.SilkS")
		)
		(fp_line
			(start -0.7874 -0.4064)
			(end 0.7874 -0.4064)
			(stroke
				(width 0.1524)
				(type default)
			)
			(layer "F.SilkS")
		)
		(fp_line
			(start 0.7874 -0.4064)
			(end 0.7874 0.4064)
			(stroke
				(width 0.1524)
				(type default)
			)
			(layer "F.SilkS")
		)
		(fp_line
			(start -0.67945 0.3048)
			(end -0.67945 -0.305054)
			(stroke
				(width 0.1)
				(type default)
			)
			(layer "F.Fab")
		)
		(fp_line
			(start -0.12065 0.3048)
			(end -0.67945 0.3048)
			(stroke
				(width 0.1)
				(type default)
			)
			(layer "F.Fab")
		)
		(fp_line
			(start 0.120396 0.3048)
			(end 0.120396 0.2794)
			(stroke
				(width 0.1)
				(type default)
			)
			(layer "F.Fab")
		)
		(fp_line
			(start 0.67945 0.3048)
			(end 0.120396 0.3048)
			(stroke
				(width 0.1)
				(type default)
			)
			(layer "F.Fab")
		)
		(fp_line
			(start -0.12065 0.2794)
			(end -0.12065 0.3048)
			(stroke
				(width 0.1)
				(type default)
			)
			(layer "F.Fab")
		)
		(fp_line
			(start 0.120396 0.2794)
			(end -0.12065 0.2794)
			(stroke
				(width 0.1)
				(type default)
			)
			(layer "F.Fab")
		)
		(fp_line
			(start -0.12065 -0.2794)
			(end 0.12065 -0.2794)
			(stroke
				(width 0.1)
				(type default)
			)
			(layer "F.Fab")
		)
		(fp_line
			(start 0.12065 -0.2794)
			(end 0.12065 -0.3048)
			(stroke
				(width 0.1)
				(type default)
			)
			(layer "F.Fab")
		)
		(fp_line
			(start 0.12065 -0.3048)
			(end 0.67945 -0.3048)
			(stroke
				(width 0.1)
				(type default)
			)
			(layer "F.Fab")
		)
		(fp_line
			(start 0.67945 -0.3048)
			(end 0.67945 0.3048)
			(stroke
				(width 0.1)
				(type default)
			)
			(layer "F.Fab")
		)
		(fp_line
			(start -0.67945 -0.305054)
			(end -0.12065 -0.305054)
			(stroke
				(width 0.1)
				(type default)
			)
			(layer "F.Fab")
		)
		(fp_line
			(start -0.12065 -0.305054)
			(end -0.12065 -0.2794)
			(stroke
				(width 0.1)
				(type default)
			)
			(layer "F.Fab")
		)
		(pad "1" smd circle
			(at -0.40005 0 270)
			(size 0 0)
			(layers "F.Cu" "F.Mask" "F.Paste")
			(net "P3V3_AUX")
		)
		(pad "2" smd circle
			(at 0.40005 0 270)
			(size 0 0)
			(layers "F.Cu" "F.Mask" "F.Paste")
			(net "GND")
		)
	)
	(footprint ""
		(layer "F.Cu")
		(at 249.643646 -70.204076)
		(property "Reference" "PC1650"
			(at 0 0 0)
			(layer "F.SilkS")
			(hide yes)
			(effects
				(font
					(size 1.27 1.27)
				)
			)
		)
		(property "Value" ""
			(at 0 0 0)
			(layer "F.Fab")
			(effects
				(font
					(size 1.27 1.27)
				)
			)
		)
		(duplicate_pad_numbers_are_jumpers no)
		(fp_line
			(start -0.7874 -0.4064)
			(end 0.7874 -0.4064)
			(stroke
				(width 0.1524)
				(type default)
			)
			(layer "F.SilkS")
		)
		(fp_line
			(start -0.7874 0.4064)
			(end -0.7874 -0.4064)
			(stroke
				(width 0.1524)
				(type default)
			)
			(layer "F.SilkS")
		)
		(fp_line
			(start 0.7874 -0.4064)
			(end 0.7874 0.4064)
			(stroke
				(width 0.1524)
				(type default)
			)
			(layer "F.SilkS")
		)
		(fp_line
			(start 0.7874 0.4064)
			(end -0.7874 0.4064)
			(stroke
				(width 0.1524)
				(type default)
			)
			(layer "F.SilkS")
		)
		(fp_line
			(start -0.67945 -0.305054)
			(end -0.12065 -0.305054)
			(stroke
				(width 0.1)
				(type default)
			)
			(layer "F.Fab")
		)
		(fp_line
			(start -0.67945 0.3048)
			(end -0.67945 -0.305054)
			(stroke
				(width 0.1)
				(type default)
			)
			(layer "F.Fab")
		)
		(fp_line
			(start -0.12065 -0.305054)
			(end -0.12065 -0.2794)
			(stroke
				(width 0.1)
				(type default)
			)
			(layer "F.Fab")
		)
		(fp_line
			(start -0.12065 -0.2794)
			(end 0.12065 -0.2794)
			(stroke
				(width 0.1)
				(type default)
			)
			(layer "F.Fab")
		)
		(fp_line
			(start -0.12065 0.2794)
			(end -0.12065 0.3048)
			(stroke
				(width 0.1)
				(type default)
			)
			(layer "F.Fab")
		)
		(fp_line
			(start -0.12065 0.3048)
			(end -0.67945 0.3048)
			(stroke
				(width 0.1)
				(type default)
			)
			(layer "F.Fab")
		)
		(fp_line
			(start 0.120396 0.2794)
			(end -0.12065 0.2794)
			(stroke
				(width 0.1)
				(type default)
			)
			(layer "F.Fab")
		)
		(fp_line
			(start 0.120396 0.3048)
			(end 0.120396 0.2794)
			(stroke
				(width 0.1)
				(type default)
			)
			(layer "F.Fab")
		)
		(fp_line
			(start 0.12065 -0.3048)
			(end 0.67945 -0.3048)
			(stroke
				(width 0.1)
				(type default)
			)
			(layer "F.Fab")
		)
		(fp_line
			(start 0.12065 -0.2794)
			(end 0.12065 -0.3048)
			(stroke
				(width 0.1)
				(type default)
			)
			(layer "F.Fab")
		)
		(fp_line
			(start 0.67945 -0.3048)
			(end 0.67945 0.3048)
			(stroke
				(width 0.1)
				(type default)
			)
			(layer "F.Fab")
		)
		(fp_line
			(start 0.67945 0.3048)
			(end 0.120396 0.3048)
			(stroke
				(width 0.1)
				(type default)
			)
			(layer "F.Fab")
		)
		(pad "1" smd circle
			(at -0.40005 0)
			(size 0 0)
			(layers "F.Cu" "F.Mask" "F.Paste")
			(net "P12V_AUX")
		)
		(pad "2" smd circle
			(at 0.40005 0)
			(size 0 0)
			(layers "F.Cu" "F.Mask" "F.Paste")
			(net "GND")
		)
	)
	(footprint ""
		(layer "F.Cu")
		(at 442.828172 -33.062418 90)
		(property "Reference" "PR3835"
			(at 0 0 90)
			(layer "F.SilkS")
			(hide yes)
			(effects
				(font
					(size 1.27 1.27)
				)
			)
		)
		(property "Value" ""
			(at 0 0 90)
			(layer "F.Fab")
			(effects
				(font
					(size 1.27 1.27)
				)
			)
		)
		(duplicate_pad_numbers_are_jumpers no)
		(fp_line
			(start 0.7874 -0.4064)
			(end 0.7874 0.4064)
			(stroke
				(width 0.1524)
				(type default)
			)
			(layer "F.SilkS")
		)
		(fp_line
			(start -0.7874 -0.4064)
			(end 0.7874 -0.4064)
			(stroke
				(width 0.1524)
				(type default)
			)
			(layer "F.SilkS")
		)
		(fp_line
			(start 0.7874 0.4064)
			(end -0.7874 0.4064)
			(stroke
				(width 0.1524)
				(type default)
			)
			(layer "F.SilkS")
		)
		(fp_line
			(start -0.7874 0.4064)
			(end -0.7874 -0.4064)
			(stroke
				(width 0.1524)
				(type default)
			)
			(layer "F.SilkS")
		)
		(fp_line
			(start -0.12065 -0.305054)
			(end -0.12065 -0.2794)
			(stroke
				(width 0.1)
				(type default)
			)
			(layer "F.Fab")
		)
		(fp_line
			(start -0.67945 -0.305054)
			(end -0.12065 -0.305054)
			(stroke
				(width 0.1)
				(type default)
			)
			(layer "F.Fab")
		)
		(fp_line
			(start 0.67945 -0.3048)
			(end 0.67945 0.3048)
			(stroke
				(width 0.1)
				(type default)
			)
			(layer "F.Fab")
		)
		(fp_line
			(start 0.12065 -0.3048)
			(end 0.67945 -0.3048)
			(stroke
				(width 0.1)
				(type default)
			)
			(layer "F.Fab")
		)
		(fp_line
			(start 0.12065 -0.2794)
			(end 0.12065 -0.3048)
			(stroke
				(width 0.1)
				(type default)
			)
			(layer "F.Fab")
		)
		(fp_line
			(start -0.12065 -0.2794)
			(end 0.12065 -0.2794)
			(stroke
				(width 0.1)
				(type default)
			)
			(layer "F.Fab")
		)
		(fp_line
			(start 0.120396 0.2794)
			(end -0.12065 0.2794)
			(stroke
				(width 0.1)
				(type default)
			)
			(layer "F.Fab")
		)
		(fp_line
			(start -0.12065 0.2794)
			(end -0.12065 0.3048)
			(stroke
				(width 0.1)
				(type default)
			)
			(layer "F.Fab")
		)
		(fp_line
			(start 0.67945 0.3048)
			(end 0.120396 0.3048)
			(stroke
				(width 0.1)
				(type default)
			)
			(layer "F.Fab")
		)
		(fp_line
			(start 0.120396 0.3048)
			(end 0.120396 0.2794)
			(stroke
				(width 0.1)
				(type default)
			)
			(layer "F.Fab")
		)
		(fp_line
			(start -0.12065 0.3048)
			(end -0.67945 0.3048)
			(stroke
				(width 0.1)
				(type default)
			)
			(layer "F.Fab")
		)
		(fp_line
			(start -0.67945 0.3048)
			(end -0.67945 -0.305054)
			(stroke
				(width 0.1)
				(type default)
			)
			(layer "F.Fab")
		)
		(pad "1" smd circle
			(at -0.40005 0 90)
			(size 0 0)
			(layers "F.Cu" "F.Mask" "F.Paste")
			(net "P12V_OCP_ISET_1")
		)
		(pad "2" smd circle
			(at 0.40005 0 90)
			(size 0 0)
			(layers "F.Cu" "F.Mask" "F.Paste")
			(net "GND")
		)
	)
	(footprint ""
		(layer "F.Cu")
		(at 350.790764 -360.934762 -90)
		(property "Reference" "R2365"
			(at 0 0 270)
			(layer "F.SilkS")
			(hide yes)
			(effects
				(font
					(size 1.27 1.27)
				)
			)
		)
		(property "Value" ""
			(at 0 0 270)
			(layer "F.Fab")
			(effects
				(font
					(size 1.27 1.27)
				)
			)
		)
		(duplicate_pad_numbers_are_jumpers no)
		(fp_line
			(start -0.7874 0.4064)
			(end -0.7874 -0.4064)
			(stroke
				(width 0.1524)
				(type default)
			)
			(layer "F.SilkS")
		)
		(fp_line
			(start 0.7874 0.4064)
			(end -0.7874 0.4064)
			(stroke
				(width 0.1524)
				(type default)
			)
			(layer "F.SilkS")
		)
		(fp_line
			(start -0.7874 -0.4064)
			(end 0.7874 -0.4064)
			(stroke
				(width 0.1524)
				(type default)
			)
			(layer "F.SilkS")
		)
		(fp_line
			(start 0.7874 -0.4064)
			(end 0.7874 0.4064)
			(stroke
				(width 0.1524)
				(type default)
			)
			(layer "F.SilkS")
		)
		(fp_line
			(start -0.67945 0.3048)
			(end -0.67945 -0.305054)
			(stroke
				(width 0.1)
				(type default)
			)
			(layer "F.Fab")
		)
		(fp_line
			(start -0.12065 0.3048)
			(end -0.67945 0.3048)
			(stroke
				(width 0.1)
				(type default)
			)
			(layer "F.Fab")
		)
		(fp_line
			(start 0.120396 0.3048)
			(end 0.120396 0.2794)
			(stroke
				(width 0.1)
				(type default)
			)
			(layer "F.Fab")
		)
		(fp_line
			(start 0.67945 0.3048)
			(end 0.120396 0.3048)
			(stroke
				(width 0.1)
				(type default)
			)
			(layer "F.Fab")
		)
		(fp_line
			(start -0.12065 0.2794)
			(end -0.12065 0.3048)
			(stroke
				(width 0.1)
				(type default)
			)
			(layer "F.Fab")
		)
		(fp_line
			(start 0.120396 0.2794)
			(end -0.12065 0.2794)
			(stroke
				(width 0.1)
				(type default)
			)
			(layer "F.Fab")
		)
		(fp_line
			(start -0.12065 -0.2794)
			(end 0.12065 -0.2794)
			(stroke
				(width 0.1)
				(type default)
			)
			(layer "F.Fab")
		)
		(fp_line
			(start 0.12065 -0.2794)
			(end 0.12065 -0.3048)
			(stroke
				(width 0.1)
				(type default)
			)
			(layer "F.Fab")
		)
		(fp_line
			(start 0.12065 -0.3048)
			(end 0.67945 -0.3048)
			(stroke
				(width 0.1)
				(type default)
			)
			(layer "F.Fab")
		)
		(fp_line
			(start 0.67945 -0.3048)
			(end 0.67945 0.3048)
			(stroke
				(width 0.1)
				(type default)
			)
			(layer "F.Fab")
		)
		(fp_line
			(start -0.67945 -0.305054)
			(end -0.12065 -0.305054)
			(stroke
				(width 0.1)
				(type default)
			)
			(layer "F.Fab")
		)
		(fp_line
			(start -0.12065 -0.305054)
			(end -0.12065 -0.2794)
			(stroke
				(width 0.1)
				(type default)
			)
			(layer "F.Fab")
		)
		(pad "1" smd circle
			(at -0.40005 0 270)
			(size 0 0)
			(layers "F.Cu" "F.Mask" "F.Paste")
			(net "P3V3_AUX")
		)
		(pad "2" smd circle
			(at 0.40005 0 270)
			(size 0 0)
			(layers "F.Cu" "F.Mask" "F.Paste")
			(net "PWRGD_PVCCIN_CPU0_R")
		)
	)
)
